(kicad_pcb
	(version 20260206)
	(generator "pcbnew")
	(generator_version "10.0")
	(general
		(thickness 1.6)
		(legacy_teardrops no)
	)
	(paper "A4")
	(title_block
		(title "04192023_DAF0TMB3IC0_F0TG_MB_C_brd_V02_OCP.brd")
		(comment 1 "Grand Teton / footprints 7169-7175 of 8354")
	)
	(layers
		(0 "F.Cu" signal "TOP")
		(4 "In1.Cu" signal "GND")
		(6 "In2.Cu" signal "IN1")
		(8 "In3.Cu" signal "GND1")
		(10 "In4.Cu" signal "IN2")
		(12 "In5.Cu" signal "GND2")
		(14 "In6.Cu" signal "IN3")
		(16 "In7.Cu" signal "GND3")
		(18 "In8.Cu" signal "VCC")
		(20 "In9.Cu" signal "VCC1")
		(22 "In10.Cu" signal "GND4")
		(24 "In11.Cu" signal "IN4")
		(26 "In12.Cu" signal "GND5")
		(28 "In13.Cu" signal "IN5")
		(30 "In14.Cu" signal "GND6")
		(32 "In15.Cu" signal "IN6")
		(34 "In16.Cu" signal "GND7")
		(2 "B.Cu" signal "BOTTOM")
		(9 "F.Adhes" user "F.Adhesive")
		(11 "B.Adhes" user "B.Adhesive")
		(13 "F.Paste" user "Package Geometry/Pastemask Top")
		(15 "B.Paste" user "Package Geometry/Pastemask Bottom")
		(5 "F.SilkS" user "Ref Des/Silkscreen Top")
		(7 "B.SilkS" user "Ref Des/Silkscreen Bottom")
		(1 "F.Mask" user "Board Geometry/Soldermask Top")
		(3 "B.Mask" user "Board Geometry/Soldermask Bottom")
		(17 "Dwgs.User" user "User.Drawings")
		(19 "Cmts.User" user "User.Comments")
		(21 "Eco1.User" user "User.Eco1")
		(23 "Eco2.User" user "User.Eco2")
		(25 "Edge.Cuts" user "Board Geometry/Outline")
		(27 "Margin" user)
		(31 "F.CrtYd" user "Package Geometry/Place Bound Top")
		(29 "B.CrtYd" user "Package Geometry/Place Bound Bottom")
		(35 "F.Fab" user "Ref Des/Assembly Top")
		(33 "B.Fab" user "Ref Des/Assembly Bottom")
	)
	(footprint ""
		(layer "B.Cu")
		(at 30.249114 -244.085364 180)
		(property "Reference" "R504"
			(at 0 0 0)
			(layer "B.SilkS")
			(hide yes)
			(effects
				(font
					(size 1.27 1.27)
				)
				(justify mirror)
			)
		)
		(property "Value" ""
			(at 0 0 0)
			(layer "B.Fab")
			(effects
				(font
					(size 1.27 1.27)
				)
				(justify mirror)
			)
		)
		(duplicate_pad_numbers_are_jumpers no)
		(fp_line
			(start 0.7874 0.4064)
			(end 0.7874 -0.4064)
			(stroke
				(width 0.1524)
				(type default)
			)
			(layer "B.SilkS")
		)
		(fp_line
			(start 0.7874 -0.4064)
			(end -0.7874 -0.4064)
			(stroke
				(width 0.1524)
				(type default)
			)
			(layer "B.SilkS")
		)
		(fp_line
			(start -0.7874 0.4064)
			(end 0.7874 0.4064)
			(stroke
				(width 0.1524)
				(type default)
			)
			(layer "B.SilkS")
		)
		(fp_line
			(start -0.7874 -0.4064)
			(end -0.7874 0.4064)
			(stroke
				(width 0.1524)
				(type default)
			)
			(layer "B.SilkS")
		)
		(fp_line
			(start 0.67945 0.3048)
			(end 0.67945 -0.305054)
			(stroke
				(width 0.1)
				(type default)
			)
			(layer "B.Fab")
		)
		(fp_line
			(start 0.67945 -0.305054)
			(end 0.12065 -0.305054)
			(stroke
				(width 0.1)
				(type default)
			)
			(layer "B.Fab")
		)
		(fp_line
			(start 0.12065 0.3048)
			(end 0.67945 0.3048)
			(stroke
				(width 0.1)
				(type default)
			)
			(layer "B.Fab")
		)
		(fp_line
			(start 0.12065 0.2794)
			(end 0.12065 0.3048)
			(stroke
				(width 0.1)
				(type default)
			)
			(layer "B.Fab")
		)
		(fp_line
			(start 0.12065 -0.2794)
			(end -0.12065 -0.2794)
			(stroke
				(width 0.1)
				(type default)
			)
			(layer "B.Fab")
		)
		(fp_line
			(start 0.12065 -0.305054)
			(end 0.12065 -0.2794)
			(stroke
				(width 0.1)
				(type default)
			)
			(layer "B.Fab")
		)
		(fp_line
			(start -0.120396 0.3048)
			(end -0.120396 0.2794)
			(stroke
				(width 0.1)
				(type default)
			)
			(layer "B.Fab")
		)
		(fp_line
			(start -0.120396 0.2794)
			(end 0.12065 0.2794)
			(stroke
				(width 0.1)
				(type default)
			)
			(layer "B.Fab")
		)
		(fp_line
			(start -0.12065 -0.2794)
			(end -0.12065 -0.3048)
			(stroke
				(width 0.1)
				(type default)
			)
			(layer "B.Fab")
		)
		(fp_line
			(start -0.12065 -0.3048)
			(end -0.67945 -0.3048)
			(stroke
				(width 0.1)
				(type default)
			)
			(layer "B.Fab")
		)
		(fp_line
			(start -0.67945 0.3048)
			(end -0.120396 0.3048)
			(stroke
				(width 0.1)
				(type default)
			)
			(layer "B.Fab")
		)
		(fp_line
			(start -0.67945 -0.3048)
			(end -0.67945 0.3048)
			(stroke
				(width 0.1)
				(type default)
			)
			(layer "B.Fab")
		)
		(pad "1" smd circle
			(at 0.40005 0)
			(size 0 0)
			(layers "B.Cu" "B.Mask" "B.Paste")
			(net "M_E_CPU1_ALERT_N")
		)
		(pad "2" smd circle
			(at -0.40005 0)
			(size 0 0)
			(layers "B.Cu" "B.Mask" "B.Paste")
			(net "M_E_CPU1_ALERT_R_N")
		)
	)
	(footprint ""
		(layer "B.Cu")
		(at 94.948502 -205.14945 90)
		(property "Reference" "R532"
			(at 0 0 90)
			(layer "B.SilkS")
			(hide yes)
			(effects
				(font
					(size 1.27 1.27)
				)
				(justify mirror)
			)
		)
		(property "Value" ""
			(at 0 0 90)
			(layer "B.Fab")
			(effects
				(font
					(size 1.27 1.27)
				)
				(justify mirror)
			)
		)
		(duplicate_pad_numbers_are_jumpers no)
		(fp_line
			(start 0.7874 -0.4064)
			(end -0.7874 -0.4064)
			(stroke
				(width 0.1524)
				(type default)
			)
			(layer "B.SilkS")
		)
		(fp_line
			(start -0.7874 -0.4064)
			(end -0.7874 0.4064)
			(stroke
				(width 0.1524)
				(type default)
			)
			(layer "B.SilkS")
		)
		(fp_line
			(start 0.7874 0.4064)
			(end 0.7874 -0.4064)
			(stroke
				(width 0.1524)
				(type default)
			)
			(layer "B.SilkS")
		)
		(fp_line
			(start -0.7874 0.4064)
			(end 0.7874 0.4064)
			(stroke
				(width 0.1524)
				(type default)
			)
			(layer "B.SilkS")
		)
		(fp_line
			(start 0.67945 -0.305054)
			(end 0.12065 -0.305054)
			(stroke
				(width 0.1)
				(type default)
			)
			(layer "B.Fab")
		)
		(fp_line
			(start 0.12065 -0.305054)
			(end 0.12065 -0.2794)
			(stroke
				(width 0.1)
				(type default)
			)
			(layer "B.Fab")
		)
		(fp_line
			(start -0.12065 -0.3048)
			(end -0.67945 -0.3048)
			(stroke
				(width 0.1)
				(type default)
			)
			(layer "B.Fab")
		)
		(fp_line
			(start -0.67945 -0.3048)
			(end -0.67945 0.3048)
			(stroke
				(width 0.1)
				(type default)
			)
			(layer "B.Fab")
		)
		(fp_line
			(start 0.12065 -0.2794)
			(end -0.12065 -0.2794)
			(stroke
				(width 0.1)
				(type default)
			)
			(layer "B.Fab")
		)
		(fp_line
			(start -0.12065 -0.2794)
			(end -0.12065 -0.3048)
			(stroke
				(width 0.1)
				(type default)
			)
			(layer "B.Fab")
		)
		(fp_line
			(start 0.12065 0.2794)
			(end 0.12065 0.3048)
			(stroke
				(width 0.1)
				(type default)
			)
			(layer "B.Fab")
		)
		(fp_line
			(start -0.120396 0.2794)
			(end 0.12065 0.2794)
			(stroke
				(width 0.1)
				(type default)
			)
			(layer "B.Fab")
		)
		(fp_line
			(start 0.67945 0.3048)
			(end 0.67945 -0.305054)
			(stroke
				(width 0.1)
				(type default)
			)
			(layer "B.Fab")
		)
		(fp_line
			(start 0.12065 0.3048)
			(end 0.67945 0.3048)
			(stroke
				(width 0.1)
				(type default)
			)
			(layer "B.Fab")
		)
		(fp_line
			(start -0.120396 0.3048)
			(end -0.120396 0.2794)
			(stroke
				(width 0.1)
				(type default)
			)
			(layer "B.Fab")
		)
		(fp_line
			(start -0.67945 0.3048)
			(end -0.120396 0.3048)
			(stroke
				(width 0.1)
				(type default)
			)
			(layer "B.Fab")
		)
		(pad "1" smd circle
			(at 0.40005 0 270)
			(size 0 0)
			(layers "B.Cu" "B.Mask" "B.Paste")
			(net "CPU1_BP1")
		)
		(pad "2" smd circle
			(at -0.40005 0 270)
			(size 0 0)
			(layers "B.Cu" "B.Mask" "B.Paste")
			(net "PVDD18_S5_P1")
		)
	)
	(footprint ""
		(layer "B.Cu")
		(at 90.706194 -386.766562 90)
		(property "Reference" "C203"
			(at 0 0 90)
			(layer "B.SilkS")
			(hide yes)
			(effects
				(font
					(size 1.27 1.27)
				)
				(justify mirror)
			)
		)
		(property "Value" ""
			(at 0 0 90)
			(layer "B.Fab")
			(effects
				(font
					(size 1.27 1.27)
				)
				(justify mirror)
			)
		)
		(duplicate_pad_numbers_are_jumpers no)
		(fp_line
			(start 0.299974 -0.150114)
			(end -0.299974 -0.150114)
			(stroke
				(width 0.1)
				(type default)
			)
			(layer "B.Fab")
		)
		(fp_line
			(start -0.299974 -0.150114)
			(end -0.299974 0.150114)
			(stroke
				(width 0.1)
				(type default)
			)
			(layer "B.Fab")
		)
		(fp_line
			(start 0.299974 0.150114)
			(end 0.299974 -0.150114)
			(stroke
				(width 0.1)
				(type default)
			)
			(layer "B.Fab")
		)
		(fp_line
			(start -0.299974 0.150114)
			(end 0.299974 0.150114)
			(stroke
				(width 0.1)
				(type default)
			)
			(layer "B.Fab")
		)
		(pad "1" smd rect
			(at 0.2667 0 270)
			(size 0.3048 0.381)
			(layers "B.Cu" "B.Mask" "B.Paste")
			(net "P1V8_CPU1_RT1_1A_1D")
		)
		(pad "2" smd rect
			(at -0.2667 0 270)
			(size 0.3048 0.381)
			(layers "B.Cu" "B.Mask" "B.Paste")
			(net "GND")
		)
	)
	(footprint ""
		(layer "B.Cu")
		(at 435.755796 -193.99631)
		(property "Reference" "R99"
			(at 0 0 0)
			(layer "B.SilkS")
			(hide yes)
			(effects
				(font
					(size 1.27 1.27)
				)
				(justify mirror)
			)
		)
		(property "Value" ""
			(at 0 0 0)
			(layer "B.Fab")
			(effects
				(font
					(size 1.27 1.27)
				)
				(justify mirror)
			)
		)
		(duplicate_pad_numbers_are_jumpers no)
		(fp_line
			(start -0.7874 -0.4064)
			(end -0.7874 0.4064)
			(stroke
				(width 0.1524)
				(type default)
			)
			(layer "B.SilkS")
		)
		(fp_line
			(start -0.7874 0.4064)
			(end 0.7874 0.4064)
			(stroke
				(width 0.1524)
				(type default)
			)
			(layer "B.SilkS")
		)
		(fp_line
			(start 0.7874 -0.4064)
			(end -0.7874 -0.4064)
			(stroke
				(width 0.1524)
				(type default)
			)
			(layer "B.SilkS")
		)
		(fp_line
			(start 0.7874 0.4064)
			(end 0.7874 -0.4064)
			(stroke
				(width 0.1524)
				(type default)
			)
			(layer "B.SilkS")
		)
		(fp_line
			(start -0.67945 -0.3048)
			(end -0.67945 0.3048)
			(stroke
				(width 0.1)
				(type default)
			)
			(layer "B.Fab")
		)
		(fp_line
			(start -0.67945 0.3048)
			(end -0.120396 0.3048)
			(stroke
				(width 0.1)
				(type default)
			)
			(layer "B.Fab")
		)
		(fp_line
			(start -0.12065 -0.3048)
			(end -0.67945 -0.3048)
			(stroke
				(width 0.1)
				(type default)
			)
			(layer "B.Fab")
		)
		(fp_line
			(start -0.12065 -0.2794)
			(end -0.12065 -0.3048)
			(stroke
				(width 0.1)
				(type default)
			)
			(layer "B.Fab")
		)
		(fp_line
			(start -0.120396 0.2794)
			(end 0.12065 0.2794)
			(stroke
				(width 0.1)
				(type default)
			)
			(layer "B.Fab")
		)
		(fp_line
			(start -0.120396 0.3048)
			(end -0.120396 0.2794)
			(stroke
				(width 0.1)
				(type default)
			)
			(layer "B.Fab")
		)
		(fp_line
			(start 0.12065 -0.305054)
			(end 0.12065 -0.2794)
			(stroke
				(width 0.1)
				(type default)
			)
			(layer "B.Fab")
		)
		(fp_line
			(start 0.12065 -0.2794)
			(end -0.12065 -0.2794)
			(stroke
				(width 0.1)
				(type default)
			)
			(layer "B.Fab")
		)
		(fp_line
			(start 0.12065 0.2794)
			(end 0.12065 0.3048)
			(stroke
				(width 0.1)
				(type default)
			)
			(layer "B.Fab")
		)
		(fp_line
			(start 0.12065 0.3048)
			(end 0.67945 0.3048)
			(stroke
				(width 0.1)
				(type default)
			)
			(layer "B.Fab")
		)
		(fp_line
			(start 0.67945 -0.305054)
			(end 0.12065 -0.305054)
			(stroke
				(width 0.1)
				(type default)
			)
			(layer "B.Fab")
		)
		(fp_line
			(start 0.67945 0.3048)
			(end 0.67945 -0.305054)
			(stroke
				(width 0.1)
				(type default)
			)
			(layer "B.Fab")
		)
		(pad "1" smd circle
			(at 0.40005 0 180)
			(size 0 0)
			(layers "B.Cu" "B.Mask" "B.Paste")
			(net "P3V3")
		)
		(pad "2" smd circle
			(at -0.40005 0 180)
			(size 0 0)
			(layers "B.Cu" "B.Mask" "B.Paste")
			(net "PWRGD_CHJ_CPU0_DIMM")
		)
	)
	(footprint ""
		(layer "B.Cu")
		(at 97.591118 -426.179996 180)
		(property "Reference" "R8003"
			(at 0 0 0)
			(layer "B.SilkS")
			(hide yes)
			(effects
				(font
					(size 1.27 1.27)
				)
				(justify mirror)
			)
		)
		(property "Value" ""
			(at 0 0 0)
			(layer "B.Fab")
			(effects
				(font
					(size 1.27 1.27)
				)
				(justify mirror)
			)
		)
		(duplicate_pad_numbers_are_jumpers no)
		(fp_line
			(start 0.7874 0.4064)
			(end 0.7874 -0.4064)
			(stroke
				(width 0.1524)
				(type default)
			)
			(layer "B.SilkS")
		)
		(fp_line
			(start 0.7874 -0.4064)
			(end -0.7874 -0.4064)
			(stroke
				(width 0.1524)
				(type default)
			)
			(layer "B.SilkS")
		)
		(fp_line
			(start -0.7874 0.4064)
			(end 0.7874 0.4064)
			(stroke
				(width 0.1524)
				(type default)
			)
			(layer "B.SilkS")
		)
		(fp_line
			(start -0.7874 -0.4064)
			(end -0.7874 0.4064)
			(stroke
				(width 0.1524)
				(type default)
			)
			(layer "B.SilkS")
		)
		(fp_line
			(start 0.67945 0.3048)
			(end 0.67945 -0.305054)
			(stroke
				(width 0.1)
				(type default)
			)
			(layer "B.Fab")
		)
		(fp_line
			(start 0.67945 -0.305054)
			(end 0.12065 -0.305054)
			(stroke
				(width 0.1)
				(type default)
			)
			(layer "B.Fab")
		)
		(fp_line
			(start 0.12065 0.3048)
			(end 0.67945 0.3048)
			(stroke
				(width 0.1)
				(type default)
			)
			(layer "B.Fab")
		)
		(fp_line
			(start 0.12065 0.2794)
			(end 0.12065 0.3048)
			(stroke
				(width 0.1)
				(type default)
			)
			(layer "B.Fab")
		)
		(fp_line
			(start 0.12065 -0.2794)
			(end -0.12065 -0.2794)
			(stroke
				(width 0.1)
				(type default)
			)
			(layer "B.Fab")
		)
		(fp_line
			(start 0.12065 -0.305054)
			(end 0.12065 -0.2794)
			(stroke
				(width 0.1)
				(type default)
			)
			(layer "B.Fab")
		)
		(fp_line
			(start -0.120396 0.3048)
			(end -0.120396 0.2794)
			(stroke
				(width 0.1)
				(type default)
			)
			(layer "B.Fab")
		)
		(fp_line
			(start -0.120396 0.2794)
			(end 0.12065 0.2794)
			(stroke
				(width 0.1)
				(type default)
			)
			(layer "B.Fab")
		)
		(fp_line
			(start -0.12065 -0.2794)
			(end -0.12065 -0.3048)
			(stroke
				(width 0.1)
				(type default)
			)
			(layer "B.Fab")
		)
		(fp_line
			(start -0.12065 -0.3048)
			(end -0.67945 -0.3048)
			(stroke
				(width 0.1)
				(type default)
			)
			(layer "B.Fab")
		)
		(fp_line
			(start -0.67945 0.3048)
			(end -0.120396 0.3048)
			(stroke
				(width 0.1)
				(type default)
			)
			(layer "B.Fab")
		)
		(fp_line
			(start -0.67945 -0.3048)
			(end -0.67945 0.3048)
			(stroke
				(width 0.1)
				(type default)
			)
			(layer "B.Fab")
		)
		(pad "1" smd circle
			(at 0.40005 0)
			(size 0 0)
			(layers "B.Cu" "B.Mask" "B.Paste")
			(net "P3V3_AUX")
		)
		(pad "2" smd circle
			(at -0.40005 0)
			(size 0 0)
			(layers "B.Cu" "B.Mask" "B.Paste")
			(net "PRSNT_SWB_ISO_N")
		)
	)
	(footprint ""
		(layer "B.Cu")
		(at 237.905544 -321.471544)
		(property "Reference" "R1238"
			(at 0 0 0)
			(layer "B.SilkS")
			(hide yes)
			(effects
				(font
					(size 1.27 1.27)
				)
				(justify mirror)
			)
		)
		(property "Value" ""
			(at 0 0 0)
			(layer "B.Fab")
			(effects
				(font
					(size 1.27 1.27)
				)
				(justify mirror)
			)
		)
		(duplicate_pad_numbers_are_jumpers no)
		(fp_line
			(start -0.7874 -0.4064)
			(end -0.7874 0.4064)
			(stroke
				(width 0.1524)
				(type default)
			)
			(layer "B.SilkS")
		)
		(fp_line
			(start -0.7874 0.4064)
			(end 0.7874 0.4064)
			(stroke
				(width 0.1524)
				(type default)
			)
			(layer "B.SilkS")
		)
		(fp_line
			(start 0.7874 -0.4064)
			(end -0.7874 -0.4064)
			(stroke
				(width 0.1524)
				(type default)
			)
			(layer "B.SilkS")
		)
		(fp_line
			(start 0.7874 0.4064)
			(end 0.7874 -0.4064)
			(stroke
				(width 0.1524)
				(type default)
			)
			(layer "B.SilkS")
		)
		(fp_line
			(start -0.67945 -0.3048)
			(end -0.67945 0.3048)
			(stroke
				(width 0.1)
				(type default)
			)
			(layer "B.Fab")
		)
		(fp_line
			(start -0.67945 0.3048)
			(end -0.120396 0.3048)
			(stroke
				(width 0.1)
				(type default)
			)
			(layer "B.Fab")
		)
		(fp_line
			(start -0.12065 -0.3048)
			(end -0.67945 -0.3048)
			(stroke
				(width 0.1)
				(type default)
			)
			(layer "B.Fab")
		)
		(fp_line
			(start -0.12065 -0.2794)
			(end -0.12065 -0.3048)
			(stroke
				(width 0.1)
				(type default)
			)
			(layer "B.Fab")
		)
		(fp_line
			(start -0.120396 0.2794)
			(end 0.12065 0.2794)
			(stroke
				(width 0.1)
				(type default)
			)
			(layer "B.Fab")
		)
		(fp_line
			(start -0.120396 0.3048)
			(end -0.120396 0.2794)
			(stroke
				(width 0.1)
				(type default)
			)
			(layer "B.Fab")
		)
		(fp_line
			(start 0.12065 -0.305054)
			(end 0.12065 -0.2794)
			(stroke
				(width 0.1)
				(type default)
			)
			(layer "B.Fab")
		)
		(fp_line
			(start 0.12065 -0.2794)
			(end -0.12065 -0.2794)
			(stroke
				(width 0.1)
				(type default)
			)
			(layer "B.Fab")
		)
		(fp_line
			(start 0.12065 0.2794)
			(end 0.12065 0.3048)
			(stroke
				(width 0.1)
				(type default)
			)
			(layer "B.Fab")
		)
		(fp_line
			(start 0.12065 0.3048)
			(end 0.67945 0.3048)
			(stroke
				(width 0.1)
				(type default)
			)
			(layer "B.Fab")
		)
		(fp_line
			(start 0.67945 -0.305054)
			(end 0.12065 -0.305054)
			(stroke
				(width 0.1)
				(type default)
			)
			(layer "B.Fab")
		)
		(fp_line
			(start 0.67945 0.3048)
			(end 0.67945 -0.305054)
			(stroke
				(width 0.1)
				(type default)
			)
			(layer "B.Fab")
		)
		(pad "1" smd circle
			(at 0.40005 0 180)
			(size 0 0)
			(layers "B.Cu" "B.Mask" "B.Paste")
			(net "P5V_AUX")
		)
		(pad "2" smd circle
			(at -0.40005 0 180)
			(size 0 0)
			(layers "B.Cu" "B.Mask" "B.Paste")
			(net "P5V_AUX_ADC")
		)
	)
	(footprint ""
		(layer "B.Cu")
		(at 317.918338 -396.393162 -90)
		(property "Reference" "C583"
			(at 0 0 90)
			(layer "B.SilkS")
			(hide yes)
			(effects
				(font
					(size 1.27 1.27)
				)
				(justify mirror)
			)
		)
		(property "Value" ""
			(at 0 0 90)
			(layer "B.Fab")
			(effects
				(font
					(size 1.27 1.27)
				)
				(justify mirror)
			)
		)
		(duplicate_pad_numbers_are_jumpers no)
		(fp_line
			(start -0.299974 0.150114)
			(end 0.299974 0.150114)
			(stroke
				(width 0.1)
				(type default)
			)
			(layer "B.Fab")
		)
		(fp_line
			(start 0.299974 0.150114)
			(end 0.299974 -0.150114)
			(stroke
				(width 0.1)
				(type default)
			)
			(layer "B.Fab")
		)
		(fp_line
			(start -0.299974 -0.150114)
			(end -0.299974 0.150114)
			(stroke
				(width 0.1)
				(type default)
			)
			(layer "B.Fab")
		)
		(fp_line
			(start 0.299974 -0.150114)
			(end -0.299974 -0.150114)
			(stroke
				(width 0.1)
				(type default)
			)
			(layer "B.Fab")
		)
		(pad "1" smd rect
			(at 0.2667 0 90)
			(size 0.3048 0.381)
			(layers "B.Cu" "B.Mask" "B.Paste")
			(net "P0V9_CPU0_RT0_2A")
		)
		(pad "2" smd rect
			(at -0.2667 0 90)
			(size 0.3048 0.381)
			(layers "B.Cu" "B.Mask" "B.Paste")
			(net "GND")
		)
	)
)
